# T6G (Grand Teton) — schematic netlist excerpt (pin names and nets, part order shuffled) for the footprints in the layout excerpt that follows; sources: Cadence DE-HDL packaged netlist, KiCad conversion of 04192023_DAF0TMB3IC0_F0TG_MB_C_brd_V02_OCP.brd

R3631  Q_RES  0 5% EMPTY  pkg 0402LF  page 141 : A = P3V3_OCP_V3_2_EN_R ; B = P3V3_OCP_EN_2
R1072  Q_RES  10K 1% CHIP  pkg 0201LF  page 298 : A = GPIO3_RT_CPU0_P2 ; B = GND
R6018  Q_RES  2K 5% EMPTY  pkg 0402LF  page 151 : A = P3V3_AUX ; B = SGPIO_SCM_DI_<0>

(kicad_pcb
	(version 20260206)
	(generator "pcbnew")
	(generator_version "10.0")
	(general
		(thickness 1.6)
		(legacy_teardrops no)
	)
	(paper "A4")
	(title_block
		(title "04192023_DAF0TMB3IC0_F0TG_MB_C_brd_V02_OCP.brd")
		(comment 1 "Grand Teton / footprints 4365-4367 of 8354")
	)
	(layers
		(0 "F.Cu" signal "TOP")
		(4 "In1.Cu" signal "GND")
		(6 "In2.Cu" signal "IN1")
		(8 "In3.Cu" signal "GND1")
		(10 "In4.Cu" signal "IN2")
		(12 "In5.Cu" signal "GND2")
		(14 "In6.Cu" signal "IN3")
		(16 "In7.Cu" signal "GND3")
		(18 "In8.Cu" signal "VCC")
		(20 "In9.Cu" signal "VCC1")
		(22 "In10.Cu" signal "GND4")
		(24 "In11.Cu" signal "IN4")
		(26 "In12.Cu" signal "GND5")
		(28 "In13.Cu" signal "IN5")
		(30 "In14.Cu" signal "GND6")
		(32 "In15.Cu" signal "IN6")
		(34 "In16.Cu" signal "GND7")
		(2 "B.Cu" signal "BOTTOM")
		(9 "F.Adhes" user "F.Adhesive")
		(11 "B.Adhes" user "B.Adhesive")
		(13 "F.Paste" user "Package Geometry/Pastemask Top")
		(15 "B.Paste" user "Package Geometry/Pastemask Bottom")
		(5 "F.SilkS" user "Ref Des/Silkscreen Top")
		(7 "B.SilkS" user "Ref Des/Silkscreen Bottom")
		(1 "F.Mask" user "Board Geometry/Soldermask Top")
		(3 "B.Mask" user "Board Geometry/Soldermask Bottom")
		(17 "Dwgs.User" user "User.Drawings")
		(19 "Cmts.User" user "User.Comments")
		(21 "Eco1.User" user "User.Eco1")
		(23 "Eco2.User" user "User.Eco2")
		(25 "Edge.Cuts" user "Board Geometry/Outline")
		(27 "Margin" user)
		(31 "F.CrtYd" user "Package Geometry/Place Bound Top")
		(29 "B.CrtYd" user "Package Geometry/Place Bound Bottom")
		(35 "F.Fab" user "Ref Des/Assembly Top")
		(33 "B.Fab" user "Ref Des/Assembly Bottom")
	)
	(footprint ""
		(layer "F.Cu")
		(at 157.037024 -26.68778 -90)
		(property "Reference" "R6018"
			(at 0 0 270)
			(layer "F.SilkS")
			(hide yes)
			(effects
				(font
					(size 1.27 1.27)
				)
			)
		)
		(property "Value" ""
			(at 0 0 270)
			(layer "F.Fab")
			(effects
				(font
					(size 1.27 1.27)
				)
			)
		)
		(duplicate_pad_numbers_are_jumpers no)
		(fp_line
			(start -0.7874 0.4064)
			(end -0.7874 -0.4064)
			(stroke
				(width 0.1524)
				(type default)
			)
			(layer "F.SilkS")
		)
		(fp_line
			(start 0.7874 0.4064)
			(end -0.7874 0.4064)
			(stroke
				(width 0.1524)
				(type default)
			)
			(layer "F.SilkS")
		)
		(fp_line
			(start -0.7874 -0.4064)
			(end 0.7874 -0.4064)
			(stroke
				(width 0.1524)
				(type default)
			)
			(layer "F.SilkS")
		)
		(fp_line
			(start 0.7874 -0.4064)
			(end 0.7874 0.4064)
			(stroke
				(width 0.1524)
				(type default)
			)
			(layer "F.SilkS")
		)
		(fp_line
			(start -0.67945 0.3048)
			(end -0.67945 -0.305054)
			(stroke
				(width 0.1)
				(type default)
			)
			(layer "F.Fab")
		)
		(fp_line
			(start -0.12065 0.3048)
			(end -0.67945 0.3048)
			(stroke
				(width 0.1)
				(type default)
			)
			(layer "F.Fab")
		)
		(fp_line
			(start 0.120396 0.3048)
			(end 0.120396 0.2794)
			(stroke
				(width 0.1)
				(type default)
			)
			(layer "F.Fab")
		)
		(fp_line
			(start 0.67945 0.3048)
			(end 0.120396 0.3048)
			(stroke
				(width 0.1)
				(type default)
			)
			(layer "F.Fab")
		)
		(fp_line
			(start -0.12065 0.2794)
			(end -0.12065 0.3048)
			(stroke
				(width 0.1)
				(type default)
			)
			(layer "F.Fab")
		)
		(fp_line
			(start 0.120396 0.2794)
			(end -0.12065 0.2794)
			(stroke
				(width 0.1)
				(type default)
			)
			(layer "F.Fab")
		)
		(fp_line
			(start -0.12065 -0.2794)
			(end 0.12065 -0.2794)
			(stroke
				(width 0.1)
				(type default)
			)
			(layer "F.Fab")
		)
		(fp_line
			(start 0.12065 -0.2794)
			(end 0.12065 -0.3048)
			(stroke
				(width 0.1)
				(type default)
			)
			(layer "F.Fab")
		)
		(fp_line
			(start 0.12065 -0.3048)
			(end 0.67945 -0.3048)
			(stroke
				(width 0.1)
				(type default)
			)
			(layer "F.Fab")
		)
		(fp_line
			(start 0.67945 -0.3048)
			(end 0.67945 0.3048)
			(stroke
				(width 0.1)
				(type default)
			)
			(layer "F.Fab")
		)
		(fp_line
			(start -0.67945 -0.305054)
			(end -0.12065 -0.305054)
			(stroke
				(width 0.1)
				(type default)
			)
			(layer "F.Fab")
		)
		(fp_line
			(start -0.12065 -0.305054)
			(end -0.12065 -0.2794)
			(stroke
				(width 0.1)
				(type default)
			)
			(layer "F.Fab")
		)
		(pad "1" smd circle
			(at -0.40005 0 270)
			(size 0 0)
			(layers "F.Cu" "F.Mask" "F.Paste")
			(net "P3V3_AUX")
		)
		(pad "2" smd circle
			(at 0.40005 0 270)
			(size 0 0)
			(layers "F.Cu" "F.Mask" "F.Paste")
			(net "SGPIO_SCM_DI_<0>")
		)
	)
	(footprint ""
		(layer "F.Cu")
		(at 398.893538 -393.04468)
		(property "Reference" "R1072"
			(at 0 0 0)
			(layer "F.SilkS")
			(hide yes)
			(effects
				(font
					(size 1.27 1.27)
				)
			)
		)
		(property "Value" ""
			(at 0 0 0)
			(layer "F.Fab")
			(effects
				(font
					(size 1.27 1.27)
				)
			)
		)
		(duplicate_pad_numbers_are_jumpers no)
		(fp_line
			(start -0.32512 -0.175006)
			(end 0.32512 -0.175006)
			(stroke
				(width 0.1)
				(type default)
			)
			(layer "F.Fab")
		)
		(fp_line
			(start -0.32512 0.175006)
			(end -0.32512 -0.175006)
			(stroke
				(width 0.1)
				(type default)
			)
			(layer "F.Fab")
		)
		(fp_line
			(start 0.32512 -0.175006)
			(end 0.32512 0.175006)
			(stroke
				(width 0.1)
				(type default)
			)
			(layer "F.Fab")
		)
		(fp_line
			(start 0.32512 0.175006)
			(end -0.32512 0.175006)
			(stroke
				(width 0.1)
				(type default)
			)
			(layer "F.Fab")
		)
		(pad "1" smd rect
			(at -0.2667 0)
			(size 0.3048 0.381)
			(layers "F.Cu" "F.Mask" "F.Paste")
			(net "GPIO3_RT_CPU0_P2")
		)
		(pad "2" smd rect
			(at 0.2667 0 180)
			(size 0.3048 0.381)
			(layers "F.Cu" "F.Mask" "F.Paste")
			(net "GND")
		)
	)
	(footprint ""
		(layer "F.Cu")
		(at 97.177352 -72.99198 180)
		(property "Reference" "R3631"
			(at 0 0 180)
			(layer "F.SilkS")
			(hide yes)
			(effects
				(font
					(size 1.27 1.27)
				)
			)
		)
		(property "Value" ""
			(at 0 0 180)
			(layer "F.Fab")
			(effects
				(font
					(size 1.27 1.27)
				)
			)
		)
		(duplicate_pad_numbers_are_jumpers no)
		(fp_line
			(start 0.7874 0.4064)
			(end -0.7874 0.4064)
			(stroke
				(width 0.1524)
				(type default)
			)
			(layer "F.SilkS")
		)
		(fp_line
			(start 0.7874 -0.4064)
			(end 0.7874 0.4064)
			(stroke
				(width 0.1524)
				(type default)
			)
			(layer "F.SilkS")
		)
		(fp_line
			(start -0.7874 0.4064)
			(end -0.7874 -0.4064)
			(stroke
				(width 0.1524)
				(type default)
			)
			(layer "F.SilkS")
		)
		(fp_line
			(start -0.7874 -0.4064)
			(end 0.7874 -0.4064)
			(stroke
				(width 0.1524)
				(type default)
			)
			(layer "F.SilkS")
		)
		(fp_line
			(start 0.67945 0.3048)
			(end 0.120396 0.3048)
			(stroke
				(width 0.1)
				(type default)
			)
			(layer "F.Fab")
		)
		(fp_line
			(start 0.67945 -0.3048)
			(end 0.67945 0.3048)
			(stroke
				(width 0.1)
				(type default)
			)
			(layer "F.Fab")
		)
		(fp_line
			(start 0.12065 -0.2794)
			(end 0.12065 -0.3048)
			(stroke
				(width 0.1)
				(type default)
			)
			(layer "F.Fab")
		)
		(fp_line
			(start 0.12065 -0.3048)
			(end 0.67945 -0.3048)
			(stroke
				(width 0.1)
				(type default)
			)
			(layer "F.Fab")
		)
		(fp_line
			(start 0.120396 0.3048)
			(end 0.120396 0.2794)
			(stroke
				(width 0.1)
				(type default)
			)
			(layer "F.Fab")
		)
		(fp_line
			(start 0.120396 0.2794)
			(end -0.12065 0.2794)
			(stroke
				(width 0.1)
				(type default)
			)
			(layer "F.Fab")
		)
		(fp_line
			(start -0.12065 0.3048)
			(end -0.67945 0.3048)
			(stroke
				(width 0.1)
				(type default)
			)
			(layer "F.Fab")
		)
		(fp_line
			(start -0.12065 0.2794)
			(end -0.12065 0.3048)
			(stroke
				(width 0.1)
				(type default)
			)
			(layer "F.Fab")
		)
		(fp_line
			(start -0.12065 -0.2794)
			(end 0.12065 -0.2794)
			(stroke
				(width 0.1)
				(type default)
			)
			(layer "F.Fab")
		)
		(fp_line
			(start -0.12065 -0.305054)
			(end -0.12065 -0.2794)
			(stroke
				(width 0.1)
				(type default)
			)
			(layer "F.Fab")
		)
		(fp_line
			(start -0.67945 0.3048)
			(end -0.67945 -0.305054)
			(stroke
				(width 0.1)
				(type default)
			)
			(layer "F.Fab")
		)
		(fp_line
			(start -0.67945 -0.305054)
			(end -0.12065 -0.305054)
			(stroke
				(width 0.1)
				(type default)
			)
			(layer "F.Fab")
		)
		(pad "1" smd circle
			(at -0.40005 0 180)
			(size 0 0)
			(layers "F.Cu" "F.Mask" "F.Paste")
			(net "P3V3_OCP_V3_2_EN_R")
		)
		(pad "2" smd circle
			(at 0.40005 0 180)
			(size 0 0)
			(layers "F.Cu" "F.Mask" "F.Paste")
			(net "P3V3_OCP_EN_2")
		)
	)
)
